#ISCELL
  mstr_misc dns *
  *
#ISCELL
  pure_quanta quanta_title_block_c *
  *
#ISCELL
  pure_quanta_power design_note *
  *
#ISCELL
  standard offpage *
  page28_i10
#ISCELL
  standard offpage *
  page28_i108
#CELL
  pure_quanta q_xtal_4p_13bi_24gnd *
  page28_i11
#ISCELL
  standard offpage *
  page28_i117
#ISCELL
  standard offpage *
  page28_i118
#CELL
  pure_quanta q_res *
  page28_i119
#ISCELL
  standard offpage *
  page28_i12
#CELL
  pure_quanta q_res *
  page28_i120
#CELL
  pure_quanta q_res *
  page28_i121
#CELL
  pure_quanta q_res *
  page28_i123
#ISCELL
  standard offpage *
  page28_i13
#ISCELL
  pure_quanta_power vcc_core *
  page28_i130
#ISCELL
  standard offpage *
  page28_i131
#ISCELL
  standard offpage *
  page28_i132
#ISCELL
  pure_quanta_power universal_gnd *
  page28_i14
#ISCELL
  pure_quanta_power universal_gnd *
  page28_i15
#ISCELL
  standard offpage *
  page28_i152
#ISCELL
  standard offpage *
  page28_i158
#ISCELL
  standard offpage *
  page28_i159
#CELL
  pure_quanta q_cap *
  page28_i16
#ISCELL
  standard offpage *
  page28_i160
#ISCELL
  standard offpage *
  page28_i161
#ISCELL
  pure_quanta_power universal_gnd *
  page28_i17
#ISCELL
  standard offpage *
  page28_i174
#CELL
  pure_quanta q_cap *
  page28_i18
#CELL
  pure_quanta genoa_sp5 *
  page28_i186
#ISCELL
  pure_quanta_power universal_gnd *
  page28_i19
#CELL
  pure_quanta q_res *
  page28_i20
#ISCELL
  standard offpage *
  page28_i203
#ISCELL
  standard offpage *
  page28_i204
#CELL
  pure_quanta q_res *
  page28_i206
#CELL
  pure_quanta q_res *
  page28_i207
#ISCELL
  standard offpage *
  page28_i208
#ISCELL
  standard offpage *
  page28_i209
#ISCELL
  standard offpage *
  page28_i21
#ISCELL
  standard offpage *
  page28_i210
#ISCELL
  standard offpage *
  page28_i22
#ISCELL
  standard offpage *
  page28_i223
#CELL
  pure_quanta q_res *
  page28_i224
#ISCELL
  standard offpage *
  page28_i225
#ISCELL
  standard offpage *
  page28_i226
#ISCELL
  standard offpage *
  page28_i227
#ISCELL
  standard offpage *
  page28_i229
#ISCELL
  standard offpage *
  page28_i23
#ISCELL
  standard offpage *
  page28_i24
#ISCELL
  standard offpage *
  page28_i283
#ISCELL
  standard offpage *
  page28_i284
#CELL
  pure_quanta q_res *
  page28_i285
#CELL
  pure_quanta q_res *
  page28_i286
#ISCELL
  standard offpage *
  page28_i287
#ISCELL
  standard offpage *
  page28_i288
#ISCELL
  standard offpage *
  page28_i289
#ISCELL
  standard offpage *
  page28_i290
#CELL
  pure_quanta q_res *
  page28_i291
#CELL
  pure_quanta q_res *
  page28_i292
#CELL
  pure_quanta q_res *
  page28_i299
#CELL
  pure_quanta q_crystal *
  page28_i3
#CELL
  pure_quanta q_res *
  page28_i300
#ISCELL
  standard offpage *
  page28_i302
#ISCELL
  standard offpage *
  page28_i303
#ISCELL
  pure_quanta_power universal_power *
  page28_i304
#CELL
  pure_quanta q_res *
  page28_i305
#CELL
  pure_quanta q_res *
  page28_i310
#CELL
  pure_quanta q_res *
  page28_i311
#CELL
  pure_quanta q_res *
  page28_i312
#CELL
  pure_quanta q_res *
  page28_i313
#CELL
  pure_quanta q_res *
  page28_i314
#CELL
  pure_quanta q_res *
  page28_i315
#CELL
  pure_quanta q_res *
  page28_i316
#ISCELL
  standard offpage *
  page28_i317
#ISCELL
  standard offpage *
  page28_i319
#ISCELL
  standard offpage *
  page28_i320
#ISCELL
  standard offpage *
  page28_i321
#ISCELL
  standard offpage *
  page28_i322
#ISCELL
  standard offpage *
  page28_i323
#ISCELL
  standard offpage *
  page28_i324
#ISCELL
  standard offpage *
  page28_i325
#ISCELL
  standard offpage *
  page28_i326
#ISCELL
  standard offpage *
  page28_i327
#ISCELL
  standard offpage *
  page28_i328
#CELL
  pure_quanta q_res *
  page28_i329
#CELL
  pure_quanta q_res *
  page28_i335
#ISCELL
  standard offpage *
  page28_i337
#ISCELL
  standard offpage *
  page28_i338
#ISCELL
  standard offpage *
  page28_i339
#CELL
  pure_quanta q_res *
  page28_i340
#ISCELL
  pure_quanta_power universal_power *
  page28_i341
#CELL
  pure_quanta q_res *
  page28_i342
#ISCELL
  pure_quanta_power universal_gnd *
  page28_i343
#CELL
  pure_quanta q_res *
  page28_i344
#CELL
  pure_quanta q_res *
  page28_i345
#ISCELL
  pure_quanta_power universal_gnd *
  page28_i346
#CELL
  pure_quanta q_res *
  page28_i347
#CELL
  pure_quanta q_res *
  page28_i348
#ISCELL
  pure_quanta_power universal_gnd *
  page28_i349
#ISCELL
  standard offpage *
  page28_i350
#ISCELL
  standard offpage *
  page28_i351
#ISCELL
  standard offpage *
  page28_i352
#ISCELL
  standard offpage *
  page28_i355
#ISCELL
  standard offpage *
  page28_i356
#CELL
  pure_quanta q_res *
  page28_i357
#CELL
  pure_quanta q_res *
  page28_i358
#ISCELL
  standard offpage *
  page28_i359
#ISCELL
  standard offpage *
  page28_i360
#ISCELL
  standard offpage *
  page28_i361
#ISCELL
  standard offpage *
  page28_i362
#CELL
  pure_quanta q_res *
  page28_i363
#CELL
  pure_quanta q_res *
  page28_i364
#ISCELL
  standard offpage *
  page28_i365
#ISCELL
  standard offpage *
  page28_i366
#CELL
  pure_quanta q_res *
  page28_i367
#CELL
  pure_quanta q_res *
  page28_i368
#ISCELL
  standard offpage *
  page28_i369
#CELL
  pure_quanta q_res *
  page28_i370
#CELL
  pure_quanta q_res *
  page28_i371
#ISCELL
  standard offpage *
  page28_i372
#CELL
  pure_quanta q_res *
  page28_i373
#ISCELL
  standard offpage *
  page28_i374
#ISCELL
  standard offpage *
  page28_i376
#ISCELL
  standard offpage *
  page28_i377
#CELL
  pure_quanta q_res *
  page28_i378
#ISCELL
  standard offpage *
  page28_i379
#CELL
  pure_quanta q_res *
  page28_i380
#CELL
  pure_quanta q_res *
  page28_i381
#CELL
  pure_quanta q_res *
  page28_i383
#CELL
  pure_quanta q_res *
  page28_i384
#CELL
  pure_quanta q_res *
  page28_i385
#CELL
  pure_quanta q_res *
  page28_i386
#CELL
  pure_quanta q_res *
  page28_i387
#ISCELL
  standard offpage *
  page28_i388
#ISCELL
  standard offpage *
  page28_i389
#ISCELL
  pure_quanta_power universal_gnd *
  page28_i4
#CELL
  pure_quanta q_cap *
  page28_i5
#CELL
  pure_quanta q_res *
  page28_i54
#ISCELL
  standard offpage *
  page28_i55
#CELL
  pure_quanta q_res *
  page28_i57
#ISCELL
  standard offpage *
  page28_i58
#CELL
  pure_quanta q_cap *
  page28_i6
#ISCELL
  standard offpage *
  page28_i61
#ISCELL
  standard offpage *
  page28_i62
#ISCELL
  standard offpage *
  page28_i65
#ISCELL
  standard offpage *
  page28_i66
#ISCELL
  standard offpage *
  page28_i68
#ISCELL
  standard offpage *
  page28_i69
#ISCELL
  pure_quanta_power universal_gnd *
  page28_i7
#ISCELL
  standard offpage *
  page28_i72
#CELL
  pure_quanta q_res *
  page28_i75
#ISCELL
  standard offpage *
  page28_i78
#ISCELL
  pure_quanta_power universal_power *
  page28_i79
#CELL
  pure_quanta q_res *
  page28_i8
#ISCELL
  standard offpage *
  page28_i80
#ISCELL
  standard offpage *
  page28_i81
#ISCELL
  pure_quanta_power universal_gnd *
  page28_i82
#CELL
  pure_quanta conn6_hbc1031l200d8h *
  page28_i83
#ISCELL
  standard offpage *
  page28_i84
#ISCELL
  standard offpage *
  page28_i85
#ISCELL
  standard offpage *
  page28_i86
#ISCELL
  standard offpage *
  page28_i87
#ISCELL
  standard offpage *
  page28_i9
